# BASEBOARD_FAB2 (Tioga Pass) — schematic netlist excerpt (pin names and nets, part order shuffled) for the footprints in the layout excerpt that follows; sources: Cadence DE-HDL packaged netlist, KiCad conversion of Wiwynn_Tioga_Pass_MB.brd

C2A3  CAP_A  47UF 4V 20% X5R  pkg 0603V  page 228 : A = PVDDQ_KLM ; B = GND
L4E2  IND-150NH-56-GP  pkg DISCRET-GA1  page 214 : S = VR_PVCCIO_CPU1_PH1_SW ; F = PVCCIO_CPU1
R1D30  RES  33.2 1% CHIP  pkg 0402  page 199 : A = IRQ_HSC_FAULT_R_N ; B = IRQ_HSC_FAULT_N

(kicad_pcb
	(version 20260206)
	(generator "pcbnew")
	(generator_version "10.0")
	(general
		(thickness 1.6)
		(legacy_teardrops no)
	)
	(paper "A4")
	(title_block
		(title "Wiwynn_Tioga_Pass_MB.brd")
		(comment 1 "Tioga Pass / footprints 2313-2315 of 4770")
	)
	(layers
		(0 "F.Cu" signal "TOP")
		(4 "In1.Cu" signal "L2GND")
		(6 "In2.Cu" signal "L3")
		(8 "In3.Cu" signal "L4GND")
		(10 "In4.Cu" signal "L5")
		(12 "In5.Cu" signal "L6GND")
		(14 "In6.Cu" signal "L7VCC")
		(16 "In7.Cu" signal "L8VCC")
		(18 "In8.Cu" signal "L9GND")
		(20 "In9.Cu" signal "L10")
		(22 "In10.Cu" signal "L11GND")
		(24 "In11.Cu" signal "L12")
		(26 "In12.Cu" signal "L13GND")
		(2 "B.Cu" signal "BOTTOM")
		(9 "F.Adhes" user "F.Adhesive")
		(11 "B.Adhes" user "B.Adhesive")
		(13 "F.Paste" user "Package Geometry/Pastemask Top")
		(15 "B.Paste" user "Package Geometry/Pastemask Bottom")
		(5 "F.SilkS" user "Ref Des/Silkscreen Top")
		(7 "B.SilkS" user "Ref Des/Silkscreen Bottom")
		(1 "F.Mask" user "Board Geometry/Soldermask Top")
		(3 "B.Mask" user "Board Geometry/Soldermask Bottom")
		(17 "Dwgs.User" user "User.Drawings")
		(19 "Cmts.User" user "User.Comments")
		(21 "Eco1.User" user "User.Eco1")
		(23 "Eco2.User" user "User.Eco2")
		(25 "Edge.Cuts" user "Board Geometry/Outline")
		(27 "Margin" user)
		(31 "F.CrtYd" user "Package Geometry/Place Bound Top")
		(29 "B.CrtYd" user "Package Geometry/Place Bound Bottom")
		(35 "F.Fab" user "Ref Des/Assembly Top")
		(33 "B.Fab" user "Ref Des/Assembly Bottom")
	)
	(footprint ""
		(layer "F.Cu")
		(at 171.242736 -54.10073 180)
		(property "Reference" "L4E2"
			(at 3.378708 -4.251706 180)
			(unlocked yes)
			(layer "F.SilkS")
			(effects
				(font
					(size 0.4064 0.254)
					(thickness 0.1524)
				)
			)
		)
		(property "Value" ""
			(at 0 0 180)
			(layer "F.Fab")
			(effects
				(font
					(size 1.27 1.27)
				)
			)
		)
		(duplicate_pad_numbers_are_jumpers no)
		(fp_line
			(start 8.3693 3.199892)
			(end -1.1303 3.199892)
			(stroke
				(width 0.1524)
				(type default)
			)
			(layer "F.SilkS")
		)
		(fp_line
			(start 8.3693 1.6637)
			(end 8.3693 3.199892)
			(stroke
				(width 0.1524)
				(type default)
			)
			(layer "F.SilkS")
		)
		(fp_line
			(start 8.3693 -3.199892)
			(end 8.3693 -1.6637)
			(stroke
				(width 0.1524)
				(type default)
			)
			(layer "F.SilkS")
		)
		(fp_line
			(start -1.1303 3.199892)
			(end -1.1303 1.6637)
			(stroke
				(width 0.1524)
				(type default)
			)
			(layer "F.SilkS")
		)
		(fp_line
			(start -1.1303 -1.6637)
			(end -1.1303 -3.199892)
			(stroke
				(width 0.1524)
				(type default)
			)
			(layer "F.SilkS")
		)
		(fp_line
			(start -1.1303 -3.199892)
			(end 8.3693 -3.199892)
			(stroke
				(width 0.1524)
				(type default)
			)
			(layer "F.SilkS")
		)
		(fp_rect
			(start -1.1303 3.199892)
			(end 8.3693 -3.199892)
			(stroke
				(width 0)
				(type default)
			)
			(fill no)
			(layer "F.CrtYd")
		)
		(fp_line
			(start 8.3693 3.199892)
			(end -1.1303 3.199892)
			(stroke
				(width 0.1)
				(type default)
			)
			(layer "F.Fab")
		)
		(fp_line
			(start 8.3693 -3.199892)
			(end 8.3693 3.199892)
			(stroke
				(width 0.1)
				(type default)
			)
			(layer "F.Fab")
		)
		(fp_line
			(start -1.1303 3.199892)
			(end -1.1303 -3.199892)
			(stroke
				(width 0.1)
				(type default)
			)
			(layer "F.Fab")
		)
		(fp_line
			(start -1.1303 -3.199892)
			(end 8.3693 -3.199892)
			(stroke
				(width 0.1)
				(type default)
			)
			(layer "F.Fab")
		)
		(pad "1" smd rect
			(at 0 0 180)
			(size 3.683 2.667)
			(layers "F.Cu" "F.Mask" "F.Paste")
			(net "VR_PVCCIO_CPU1_PH1_SW")
		)
		(pad "2" smd rect
			(at 7.239 0 180)
			(size 3.683 2.667)
			(layers "F.Cu" "F.Mask" "F.Paste")
			(net "PVCCIO_CPU1")
		)
	)
	(footprint ""
		(layer "F.Cu")
		(at 87.158068 -149.8092 -90)
		(property "Reference" "C2A3"
			(at 1.848866 0.752348 270)
			(unlocked yes)
			(layer "F.SilkS")
			(effects
				(font
					(size 1.27 0.9652)
					(thickness 0.1524)
				)
			)
		)
		(property "Value" ""
			(at 0 0 270)
			(layer "F.Fab")
			(effects
				(font
					(size 1.27 1.27)
				)
			)
		)
		(duplicate_pad_numbers_are_jumpers no)
		(fp_rect
			(start -0.500126 1.598422)
			(end 0.500126 -0.201422)
			(stroke
				(width 0)
				(type default)
			)
			(fill no)
			(layer "F.CrtYd")
		)
		(fp_line
			(start -0.500126 1.598422)
			(end -0.500126 -0.201422)
			(stroke
				(width 0.1)
				(type default)
			)
			(layer "F.Fab")
		)
		(fp_line
			(start 0.500126 1.598422)
			(end -0.500126 1.598422)
			(stroke
				(width 0.1)
				(type default)
			)
			(layer "F.Fab")
		)
		(fp_line
			(start -0.500126 -0.201422)
			(end 0.500126 -0.201422)
			(stroke
				(width 0.1)
				(type default)
			)
			(layer "F.Fab")
		)
		(fp_line
			(start 0.500126 -0.201422)
			(end 0.500126 1.598422)
			(stroke
				(width 0.1)
				(type default)
			)
			(layer "F.Fab")
		)
		(pad "1" smd rect
			(at 0 0 180)
			(size 0.889 0.9906)
			(layers "F.Cu" "F.Mask" "F.Paste")
			(net "PVDDQ_KLM")
		)
		(pad "2" smd rect
			(at 0 1.397 180)
			(size 0.889 0.9906)
			(layers "F.Cu" "F.Mask" "F.Paste")
			(net "GND")
		)
		(zone
			(layer "F.Cu")
			(hatch none 0.5)
			(connect_pads
				(clearance 0)
			)
			(min_thickness 0.25)
			(keepout
				(tracks not_allowed)
				(vias allowed)
				(pads allowed)
				(copperpour not_allowed)
				(footprints allowed)
			)
			(placement
				(enabled no)
				(sheetname "")
			)
			(fill
				(thermal_gap 0.5)
				(thermal_bridge_width 0.5)
				(island_removal_mode 0)
			)
			(polygon
				(pts
					(xy 86.205568 -150.3045) (xy 86.205568 -149.3139) (xy 86.713568 -149.3139) (xy 86.713568 -150.3045)
				)
			)
		)
		(zone
			(layer "F.Cu")
			(hatch none 0.5)
			(connect_pads
				(clearance 0)
			)
			(min_thickness 0.25)
			(keepout
				(tracks allowed)
				(vias not_allowed)
				(pads allowed)
				(copperpour not_allowed)
				(footprints allowed)
			)
			(placement
				(enabled no)
				(sheetname "")
			)
			(fill
				(thermal_gap 0.5)
				(thermal_bridge_width 0.5)
				(island_removal_mode 0)
			)
			(polygon
				(pts
					(xy 86.205568 -150.3045) (xy 86.205568 -149.3139) (xy 86.713568 -149.3139) (xy 86.713568 -150.3045)
				)
			)
		)
	)
	(footprint ""
		(layer "F.Cu")
		(at 22.225 -77.724 90)
		(property "Reference" "R1D30"
			(at 0 0 90)
			(layer "F.SilkS")
			(hide yes)
			(effects
				(font
					(size 1.27 1.27)
				)
			)
		)
		(property "Value" ""
			(at 0 0 90)
			(layer "F.Fab")
			(effects
				(font
					(size 1.27 1.27)
				)
			)
		)
		(duplicate_pad_numbers_are_jumpers no)
		(fp_poly
			(pts
				(xy -0.2794 -0.1016) (xy 0.2794 -0.1016) (xy 0.2794 0.9906) (xy -0.2794 0.9906)
			)
			(stroke
				(width 0)
				(type default)
			)
			(fill no)
			(layer "F.CrtYd")
		)
		(fp_line
			(start 0.2794 -0.1016)
			(end -0.2794 -0.1016)
			(stroke
				(width 0.1)
				(type default)
			)
			(layer "F.Fab")
		)
		(fp_line
			(start -0.2794 -0.1016)
			(end -0.2794 0.9906)
			(stroke
				(width 0.1)
				(type default)
			)
			(layer "F.Fab")
		)
		(fp_line
			(start 0.2794 0.9906)
			(end 0.2794 -0.1016)
			(stroke
				(width 0.1)
				(type default)
			)
			(layer "F.Fab")
		)
		(fp_line
			(start -0.2794 0.9906)
			(end 0.2794 0.9906)
			(stroke
				(width 0.1)
				(type default)
			)
			(layer "F.Fab")
		)
		(pad "1" smd rect
			(at 0 0 90)
			(size 0.508 0.508)
			(layers "F.Cu" "F.Mask" "F.Paste")
			(net "IRQ_HSC_FAULT_R_N")
		)
		(pad "2" smd rect
			(at 0 0.889 90)
			(size 0.508 0.508)
			(layers "F.Cu" "F.Mask" "F.Paste")
			(net "IRQ_HSC_FAULT_N")
		)
		(zone
			(layer "F.Cu")
			(hatch none 0.5)
			(connect_pads
				(clearance 0)
			)
			(min_thickness 0.25)
			(keepout
				(tracks allowed)
				(vias not_allowed)
				(pads allowed)
				(copperpour not_allowed)
				(footprints allowed)
			)
			(placement
				(enabled no)
				(sheetname "")
			)
			(fill
				(thermal_gap 0.5)
				(thermal_bridge_width 0.5)
				(island_removal_mode 0)
			)
			(polygon
				(pts
					(xy 22.479 -77.47) (xy 22.479 -77.978) (xy 22.86 -77.978) (xy 22.86 -77.47)
				)
			)
		)
		(zone
			(layer "F.Cu")
			(hatch none 0.5)
			(connect_pads
				(clearance 0)
			)
			(min_thickness 0.25)
			(keepout
				(tracks not_allowed)
				(vias allowed)
				(pads allowed)
				(copperpour not_allowed)
				(footprints allowed)
			)
			(placement
				(enabled no)
				(sheetname "")
			)
			(fill
				(thermal_gap 0.5)
				(thermal_bridge_width 0.5)
				(island_removal_mode 0)
			)
			(polygon
				(pts
					(xy 22.86 -77.47) (xy 22.86 -77.978) (xy 22.479 -77.978) (xy 22.479 -77.47)
				)
			)
		)
	)
)
